(kicad_pcb
	(version 20260206)
	(generator "pcbnew")
	(generator_version "10.0")
	(general
		(thickness 1.6)
		(legacy_teardrops no)
	)
	(paper "A4")
	(title_block
		(title "04192023_DAF0TMB3IC0_F0TG_MB_C_brd_V02_OCP.brd")
		(comment 1 "Grand Teton / footprints 315-321 of 8354")
	)
	(layers
		(0 "F.Cu" signal "TOP")
		(4 "In1.Cu" signal "GND")
		(6 "In2.Cu" signal "IN1")
		(8 "In3.Cu" signal "GND1")
		(10 "In4.Cu" signal "IN2")
		(12 "In5.Cu" signal "GND2")
		(14 "In6.Cu" signal "IN3")
		(16 "In7.Cu" signal "GND3")
		(18 "In8.Cu" signal "VCC")
		(20 "In9.Cu" signal "VCC1")
		(22 "In10.Cu" signal "GND4")
		(24 "In11.Cu" signal "IN4")
		(26 "In12.Cu" signal "GND5")
		(28 "In13.Cu" signal "IN5")
		(30 "In14.Cu" signal "GND6")
		(32 "In15.Cu" signal "IN6")
		(34 "In16.Cu" signal "GND7")
		(2 "B.Cu" signal "BOTTOM")
		(9 "F.Adhes" user "F.Adhesive")
		(11 "B.Adhes" user "B.Adhesive")
		(13 "F.Paste" user "Package Geometry/Pastemask Top")
		(15 "B.Paste" user "Package Geometry/Pastemask Bottom")
		(5 "F.SilkS" user "Ref Des/Silkscreen Top")
		(7 "B.SilkS" user "Ref Des/Silkscreen Bottom")
		(1 "F.Mask" user "Board Geometry/Soldermask Top")
		(3 "B.Mask" user "Board Geometry/Soldermask Bottom")
		(17 "Dwgs.User" user "User.Drawings")
		(19 "Cmts.User" user "User.Comments")
		(21 "Eco1.User" user "User.Eco1")
		(23 "Eco2.User" user "User.Eco2")
		(25 "Edge.Cuts" user "Board Geometry/Outline")
		(27 "Margin" user)
		(31 "F.CrtYd" user "Package Geometry/Place Bound Top")
		(29 "B.CrtYd" user "Package Geometry/Place Bound Bottom")
		(35 "F.Fab" user "Ref Des/Assembly Top")
		(33 "B.Fab" user "Ref Des/Assembly Bottom")
	)
	(footprint ""
		(layer "F.Cu")
		(at 35.881818 -437.449214 180)
		(property "Reference" "R3521"
			(at 0 0 180)
			(layer "F.SilkS")
			(hide yes)
			(effects
				(font
					(size 1.27 1.27)
				)
			)
		)
		(property "Value" ""
			(at 0 0 180)
			(layer "F.Fab")
			(effects
				(font
					(size 1.27 1.27)
				)
			)
		)
		(duplicate_pad_numbers_are_jumpers no)
		(fp_line
			(start 0.7874 0.4064)
			(end -0.7874 0.4064)
			(stroke
				(width 0.1524)
				(type default)
			)
			(layer "F.SilkS")
		)
		(fp_line
			(start 0.7874 -0.4064)
			(end 0.7874 0.4064)
			(stroke
				(width 0.1524)
				(type default)
			)
			(layer "F.SilkS")
		)
		(fp_line
			(start -0.7874 0.4064)
			(end -0.7874 -0.4064)
			(stroke
				(width 0.1524)
				(type default)
			)
			(layer "F.SilkS")
		)
		(fp_line
			(start -0.7874 -0.4064)
			(end 0.7874 -0.4064)
			(stroke
				(width 0.1524)
				(type default)
			)
			(layer "F.SilkS")
		)
		(fp_line
			(start 0.67945 0.3048)
			(end 0.120396 0.3048)
			(stroke
				(width 0.1)
				(type default)
			)
			(layer "F.Fab")
		)
		(fp_line
			(start 0.67945 -0.3048)
			(end 0.67945 0.3048)
			(stroke
				(width 0.1)
				(type default)
			)
			(layer "F.Fab")
		)
		(fp_line
			(start 0.12065 -0.2794)
			(end 0.12065 -0.3048)
			(stroke
				(width 0.1)
				(type default)
			)
			(layer "F.Fab")
		)
		(fp_line
			(start 0.12065 -0.3048)
			(end 0.67945 -0.3048)
			(stroke
				(width 0.1)
				(type default)
			)
			(layer "F.Fab")
		)
		(fp_line
			(start 0.120396 0.3048)
			(end 0.120396 0.2794)
			(stroke
				(width 0.1)
				(type default)
			)
			(layer "F.Fab")
		)
		(fp_line
			(start 0.120396 0.2794)
			(end -0.12065 0.2794)
			(stroke
				(width 0.1)
				(type default)
			)
			(layer "F.Fab")
		)
		(fp_line
			(start -0.12065 0.3048)
			(end -0.67945 0.3048)
			(stroke
				(width 0.1)
				(type default)
			)
			(layer "F.Fab")
		)
		(fp_line
			(start -0.12065 0.2794)
			(end -0.12065 0.3048)
			(stroke
				(width 0.1)
				(type default)
			)
			(layer "F.Fab")
		)
		(fp_line
			(start -0.12065 -0.2794)
			(end 0.12065 -0.2794)
			(stroke
				(width 0.1)
				(type default)
			)
			(layer "F.Fab")
		)
		(fp_line
			(start -0.12065 -0.305054)
			(end -0.12065 -0.2794)
			(stroke
				(width 0.1)
				(type default)
			)
			(layer "F.Fab")
		)
		(fp_line
			(start -0.67945 0.3048)
			(end -0.67945 -0.305054)
			(stroke
				(width 0.1)
				(type default)
			)
			(layer "F.Fab")
		)
		(fp_line
			(start -0.67945 -0.305054)
			(end -0.12065 -0.305054)
			(stroke
				(width 0.1)
				(type default)
			)
			(layer "F.Fab")
		)
		(pad "1" smd circle
			(at -0.40005 0 180)
			(size 0 0)
			(layers "F.Cu" "F.Mask" "F.Paste")
			(net "P3V3_AUX")
		)
		(pad "2" smd circle
			(at 0.40005 0 180)
			(size 0 0)
			(layers "F.Cu" "F.Mask" "F.Paste")
			(net "SMB_2_BMC_GPU_BUF_R_SCL")
		)
	)
	(footprint ""
		(layer "F.Cu")
		(at 279.513792 -124.305314 180)
		(property "Reference" "R587"
			(at 0 0 180)
			(layer "F.SilkS")
			(hide yes)
			(effects
				(font
					(size 1.27 1.27)
				)
			)
		)
		(property "Value" ""
			(at 0 0 180)
			(layer "F.Fab")
			(effects
				(font
					(size 1.27 1.27)
				)
			)
		)
		(duplicate_pad_numbers_are_jumpers no)
		(fp_line
			(start 0.7874 0.4064)
			(end -0.7874 0.4064)
			(stroke
				(width 0.1524)
				(type default)
			)
			(layer "F.SilkS")
		)
		(fp_line
			(start 0.7874 -0.4064)
			(end 0.7874 0.4064)
			(stroke
				(width 0.1524)
				(type default)
			)
			(layer "F.SilkS")
		)
		(fp_line
			(start -0.7874 0.4064)
			(end -0.7874 -0.4064)
			(stroke
				(width 0.1524)
				(type default)
			)
			(layer "F.SilkS")
		)
		(fp_line
			(start -0.7874 -0.4064)
			(end 0.7874 -0.4064)
			(stroke
				(width 0.1524)
				(type default)
			)
			(layer "F.SilkS")
		)
		(fp_line
			(start 0.67945 0.3048)
			(end 0.120396 0.3048)
			(stroke
				(width 0.1)
				(type default)
			)
			(layer "F.Fab")
		)
		(fp_line
			(start 0.67945 -0.3048)
			(end 0.67945 0.3048)
			(stroke
				(width 0.1)
				(type default)
			)
			(layer "F.Fab")
		)
		(fp_line
			(start 0.12065 -0.2794)
			(end 0.12065 -0.3048)
			(stroke
				(width 0.1)
				(type default)
			)
			(layer "F.Fab")
		)
		(fp_line
			(start 0.12065 -0.3048)
			(end 0.67945 -0.3048)
			(stroke
				(width 0.1)
				(type default)
			)
			(layer "F.Fab")
		)
		(fp_line
			(start 0.120396 0.3048)
			(end 0.120396 0.2794)
			(stroke
				(width 0.1)
				(type default)
			)
			(layer "F.Fab")
		)
		(fp_line
			(start 0.120396 0.2794)
			(end -0.12065 0.2794)
			(stroke
				(width 0.1)
				(type default)
			)
			(layer "F.Fab")
		)
		(fp_line
			(start -0.12065 0.3048)
			(end -0.67945 0.3048)
			(stroke
				(width 0.1)
				(type default)
			)
			(layer "F.Fab")
		)
		(fp_line
			(start -0.12065 0.2794)
			(end -0.12065 0.3048)
			(stroke
				(width 0.1)
				(type default)
			)
			(layer "F.Fab")
		)
		(fp_line
			(start -0.12065 -0.2794)
			(end 0.12065 -0.2794)
			(stroke
				(width 0.1)
				(type default)
			)
			(layer "F.Fab")
		)
		(fp_line
			(start -0.12065 -0.305054)
			(end -0.12065 -0.2794)
			(stroke
				(width 0.1)
				(type default)
			)
			(layer "F.Fab")
		)
		(fp_line
			(start -0.67945 0.3048)
			(end -0.67945 -0.305054)
			(stroke
				(width 0.1)
				(type default)
			)
			(layer "F.Fab")
		)
		(fp_line
			(start -0.67945 -0.305054)
			(end -0.12065 -0.305054)
			(stroke
				(width 0.1)
				(type default)
			)
			(layer "F.Fab")
		)
		(pad "1" smd circle
			(at -0.40005 0 180)
			(size 0 0)
			(layers "F.Cu" "F.Mask" "F.Paste")
			(net "PCA9548_PCIE3_ADDR0")
		)
		(pad "2" smd circle
			(at 0.40005 0 180)
			(size 0 0)
			(layers "F.Cu" "F.Mask" "F.Paste")
			(net "GND")
		)
	)
	(footprint ""
		(layer "F.Cu")
		(at 12.769088 -373.44985 -90)
		(property "Reference" "PC6629"
			(at 4.41452 2.355088 0)
			(unlocked yes)
			(layer "F.SilkS")
			(effects
				(font
					(size 0.7874 0.5842)
					(thickness 0.1524)
				)
				(justify left)
			)
		)
		(property "Value" ""
			(at 0 0 270)
			(layer "F.Fab")
			(effects
				(font
					(size 1.27 1.27)
				)
			)
		)
		(duplicate_pad_numbers_are_jumpers no)
		(fp_line
			(start -1.988058 2.750058)
			(end 2.750058 2.750058)
			(stroke
				(width 0.1524)
				(type default)
			)
			(layer "F.SilkS")
		)
		(fp_line
			(start 2.750058 2.750058)
			(end 2.750058 0.9398)
			(stroke
				(width 0.1524)
				(type default)
			)
			(layer "F.SilkS")
		)
		(fp_line
			(start -2.750058 1.988058)
			(end -1.988058 2.750058)
			(stroke
				(width 0.1524)
				(type default)
			)
			(layer "F.SilkS")
		)
		(fp_line
			(start -2.750058 0.9398)
			(end -2.750058 1.988058)
			(stroke
				(width 0.1524)
				(type default)
			)
			(layer "F.SilkS")
		)
		(fp_line
			(start 2.750058 -0.9398)
			(end 2.750058 -2.750058)
			(stroke
				(width 0.1524)
				(type default)
			)
			(layer "F.SilkS")
		)
		(fp_line
			(start -2.750058 -1.988058)
			(end -2.750058 -0.9398)
			(stroke
				(width 0.1524)
				(type default)
			)
			(layer "F.SilkS")
		)
		(fp_line
			(start -1.988058 -2.750058)
			(end -2.750058 -1.988058)
			(stroke
				(width 0.1524)
				(type default)
			)
			(layer "F.SilkS")
		)
		(fp_line
			(start 2.750058 -2.750058)
			(end -1.988058 -2.750058)
			(stroke
				(width 0.1524)
				(type default)
			)
			(layer "F.SilkS")
		)
		(fp_line
			(start -2.750058 2.750058)
			(end 2.750058 2.750058)
			(stroke
				(width 0.1)
				(type default)
			)
			(layer "F.Fab")
		)
		(fp_line
			(start 2.750058 2.750058)
			(end 2.750058 -2.750058)
			(stroke
				(width 0.1)
				(type default)
			)
			(layer "F.Fab")
		)
		(fp_line
			(start -2.750058 -2.750058)
			(end -2.750058 2.750058)
			(stroke
				(width 0.1)
				(type default)
			)
			(layer "F.Fab")
		)
		(fp_line
			(start 2.750058 -2.750058)
			(end -2.750058 -2.750058)
			(stroke
				(width 0.1)
				(type default)
			)
			(layer "F.Fab")
		)
		(pad "1" smd rect
			(at -2.199894 0)
			(size 1.6002 3.0226)
			(layers "F.Cu" "F.Mask" "F.Paste")
			(net "P0V9_CPU1_RT_2D")
		)
		(pad "2" smd rect
			(at 2.199894 0)
			(size 1.6002 3.0226)
			(layers "F.Cu" "F.Mask" "F.Paste")
			(net "GND")
		)
	)
	(footprint ""
		(layer "F.Cu")
		(at 118.11 -400.3548)
		(property "Reference" "R1451"
			(at 0 0 0)
			(layer "F.SilkS")
			(hide yes)
			(effects
				(font
					(size 1.27 1.27)
				)
			)
		)
		(property "Value" ""
			(at 0 0 0)
			(layer "F.Fab")
			(effects
				(font
					(size 1.27 1.27)
				)
			)
		)
		(duplicate_pad_numbers_are_jumpers no)
		(fp_line
			(start -0.32512 -0.175006)
			(end 0.32512 -0.175006)
			(stroke
				(width 0.1)
				(type default)
			)
			(layer "F.Fab")
		)
		(fp_line
			(start -0.32512 0.175006)
			(end -0.32512 -0.175006)
			(stroke
				(width 0.1)
				(type default)
			)
			(layer "F.Fab")
		)
		(fp_line
			(start 0.32512 -0.175006)
			(end 0.32512 0.175006)
			(stroke
				(width 0.1)
				(type default)
			)
			(layer "F.Fab")
		)
		(fp_line
			(start 0.32512 0.175006)
			(end -0.32512 0.175006)
			(stroke
				(width 0.1)
				(type default)
			)
			(layer "F.Fab")
		)
		(pad "1" smd rect
			(at -0.2667 0)
			(size 0.3048 0.381)
			(layers "F.Cu" "F.Mask" "F.Paste")
			(net "P1V8_CPU1_RT_1D")
		)
		(pad "2" smd rect
			(at 0.2667 0 180)
			(size 0.3048 0.381)
			(layers "F.Cu" "F.Mask" "F.Paste")
			(net "SMB_RT_CPU1_P1_ROM_MUX_1D_SCL")
		)
	)
	(footprint ""
		(layer "F.Cu")
		(at 420.246302 -436.164736 -90)
		(property "Reference" "R4158"
			(at 0 0 270)
			(layer "F.SilkS")
			(hide yes)
			(effects
				(font
					(size 1.27 1.27)
				)
			)
		)
		(property "Value" ""
			(at 0 0 270)
			(layer "F.Fab")
			(effects
				(font
					(size 1.27 1.27)
				)
			)
		)
		(duplicate_pad_numbers_are_jumpers no)
		(fp_line
			(start -0.7874 0.4064)
			(end -0.7874 -0.4064)
			(stroke
				(width 0.1524)
				(type default)
			)
			(layer "F.SilkS")
		)
		(fp_line
			(start 0.7874 0.4064)
			(end -0.7874 0.4064)
			(stroke
				(width 0.1524)
				(type default)
			)
			(layer "F.SilkS")
		)
		(fp_line
			(start -0.7874 -0.4064)
			(end 0.7874 -0.4064)
			(stroke
				(width 0.1524)
				(type default)
			)
			(layer "F.SilkS")
		)
		(fp_line
			(start 0.7874 -0.4064)
			(end 0.7874 0.4064)
			(stroke
				(width 0.1524)
				(type default)
			)
			(layer "F.SilkS")
		)
		(fp_line
			(start -0.67945 0.3048)
			(end -0.67945 -0.305054)
			(stroke
				(width 0.1)
				(type default)
			)
			(layer "F.Fab")
		)
		(fp_line
			(start -0.12065 0.3048)
			(end -0.67945 0.3048)
			(stroke
				(width 0.1)
				(type default)
			)
			(layer "F.Fab")
		)
		(fp_line
			(start 0.120396 0.3048)
			(end 0.120396 0.2794)
			(stroke
				(width 0.1)
				(type default)
			)
			(layer "F.Fab")
		)
		(fp_line
			(start 0.67945 0.3048)
			(end 0.120396 0.3048)
			(stroke
				(width 0.1)
				(type default)
			)
			(layer "F.Fab")
		)
		(fp_line
			(start -0.12065 0.2794)
			(end -0.12065 0.3048)
			(stroke
				(width 0.1)
				(type default)
			)
			(layer "F.Fab")
		)
		(fp_line
			(start 0.120396 0.2794)
			(end -0.12065 0.2794)
			(stroke
				(width 0.1)
				(type default)
			)
			(layer "F.Fab")
		)
		(fp_line
			(start -0.12065 -0.2794)
			(end 0.12065 -0.2794)
			(stroke
				(width 0.1)
				(type default)
			)
			(layer "F.Fab")
		)
		(fp_line
			(start 0.12065 -0.2794)
			(end 0.12065 -0.3048)
			(stroke
				(width 0.1)
				(type default)
			)
			(layer "F.Fab")
		)
		(fp_line
			(start 0.12065 -0.3048)
			(end 0.67945 -0.3048)
			(stroke
				(width 0.1)
				(type default)
			)
			(layer "F.Fab")
		)
		(fp_line
			(start 0.67945 -0.3048)
			(end 0.67945 0.3048)
			(stroke
				(width 0.1)
				(type default)
			)
			(layer "F.Fab")
		)
		(fp_line
			(start -0.67945 -0.305054)
			(end -0.12065 -0.305054)
			(stroke
				(width 0.1)
				(type default)
			)
			(layer "F.Fab")
		)
		(fp_line
			(start -0.12065 -0.305054)
			(end -0.12065 -0.2794)
			(stroke
				(width 0.1)
				(type default)
			)
			(layer "F.Fab")
		)
		(pad "1" smd circle
			(at -0.40005 0 270)
			(size 0 0)
			(layers "F.Cu" "F.Mask" "F.Paste")
			(net "P3V3_AUX")
		)
		(pad "2" smd circle
			(at 0.40005 0 270)
			(size 0 0)
			(layers "F.Cu" "F.Mask" "F.Paste")
			(net "GPU_3V3IO_RSVD1")
		)
	)
	(footprint ""
		(layer "F.Cu")
		(at 398.06245 -146.148552 -90)
		(property "Reference" "C1331"
			(at 0 0 270)
			(layer "F.SilkS")
			(hide yes)
			(effects
				(font
					(size 1.27 1.27)
				)
			)
		)
		(property "Value" ""
			(at 0 0 270)
			(layer "F.Fab")
			(effects
				(font
					(size 1.27 1.27)
				)
			)
		)
		(duplicate_pad_numbers_are_jumpers no)
		(fp_line
			(start -1.524 0.762)
			(end -1.524 -0.762)
			(stroke
				(width 0.1524)
				(type default)
			)
			(layer "F.SilkS")
		)
		(fp_line
			(start 1.524 0.762)
			(end -1.524 0.762)
			(stroke
				(width 0.1524)
				(type default)
			)
			(layer "F.SilkS")
		)
		(fp_line
			(start -1.524 -0.762)
			(end 1.524 -0.762)
			(stroke
				(width 0.1524)
				(type default)
			)
			(layer "F.SilkS")
		)
		(fp_line
			(start 1.524 -0.762)
			(end 1.524 0.762)
			(stroke
				(width 0.1524)
				(type default)
			)
			(layer "F.SilkS")
		)
		(fp_line
			(start -1.1049 0.724916)
			(end 1.1049 0.724916)
			(stroke
				(width 0.1)
				(type default)
			)
			(layer "F.Fab")
		)
		(fp_line
			(start 1.1049 0.724916)
			(end 1.1049 -0.724916)
			(stroke
				(width 0.1)
				(type default)
			)
			(layer "F.Fab")
		)
		(fp_line
			(start -1.1049 -0.724916)
			(end -1.1049 0.724916)
			(stroke
				(width 0.1)
				(type default)
			)
			(layer "F.Fab")
		)
		(fp_line
			(start 1.1049 -0.724916)
			(end -1.1049 -0.724916)
			(stroke
				(width 0.1)
				(type default)
			)
			(layer "F.Fab")
		)
		(pad "1" smd rect
			(at -0.889 0 90)
			(size 1.016 1.27)
			(layers "F.Cu" "F.Mask" "F.Paste")
			(net "P5V")
		)
		(pad "2" smd rect
			(at 0.889 0 90)
			(size 1.016 1.27)
			(layers "F.Cu" "F.Mask" "F.Paste")
			(net "GND")
		)
	)
	(footprint ""
		(layer "F.Cu")
		(at 145.823178 -75.115166 90)
		(property "Reference" "R6243"
			(at 0 0 90)
			(layer "F.SilkS")
			(hide yes)
			(effects
				(font
					(size 1.27 1.27)
				)
			)
		)
		(property "Value" ""
			(at 0 0 90)
			(layer "F.Fab")
			(effects
				(font
					(size 1.27 1.27)
				)
			)
		)
		(duplicate_pad_numbers_are_jumpers no)
		(fp_line
			(start 0.7874 -0.4064)
			(end 0.7874 0.4064)
			(stroke
				(width 0.1524)
				(type default)
			)
			(layer "F.SilkS")
		)
		(fp_line
			(start -0.7874 -0.4064)
			(end 0.7874 -0.4064)
			(stroke
				(width 0.1524)
				(type default)
			)
			(layer "F.SilkS")
		)
		(fp_line
			(start 0.7874 0.4064)
			(end -0.7874 0.4064)
			(stroke
				(width 0.1524)
				(type default)
			)
			(layer "F.SilkS")
		)
		(fp_line
			(start -0.7874 0.4064)
			(end -0.7874 -0.4064)
			(stroke
				(width 0.1524)
				(type default)
			)
			(layer "F.SilkS")
		)
		(fp_line
			(start -0.12065 -0.305054)
			(end -0.12065 -0.2794)
			(stroke
				(width 0.1)
				(type default)
			)
			(layer "F.Fab")
		)
		(fp_line
			(start -0.67945 -0.305054)
			(end -0.12065 -0.305054)
			(stroke
				(width 0.1)
				(type default)
			)
			(layer "F.Fab")
		)
		(fp_line
			(start 0.67945 -0.3048)
			(end 0.67945 0.3048)
			(stroke
				(width 0.1)
				(type default)
			)
			(layer "F.Fab")
		)
		(fp_line
			(start 0.12065 -0.3048)
			(end 0.67945 -0.3048)
			(stroke
				(width 0.1)
				(type default)
			)
			(layer "F.Fab")
		)
		(fp_line
			(start 0.12065 -0.2794)
			(end 0.12065 -0.3048)
			(stroke
				(width 0.1)
				(type default)
			)
			(layer "F.Fab")
		)
		(fp_line
			(start -0.12065 -0.2794)
			(end 0.12065 -0.2794)
			(stroke
				(width 0.1)
				(type default)
			)
			(layer "F.Fab")
		)
		(fp_line
			(start 0.120396 0.2794)
			(end -0.12065 0.2794)
			(stroke
				(width 0.1)
				(type default)
			)
			(layer "F.Fab")
		)
		(fp_line
			(start -0.12065 0.2794)
			(end -0.12065 0.3048)
			(stroke
				(width 0.1)
				(type default)
			)
			(layer "F.Fab")
		)
		(fp_line
			(start 0.67945 0.3048)
			(end 0.120396 0.3048)
			(stroke
				(width 0.1)
				(type default)
			)
			(layer "F.Fab")
		)
		(fp_line
			(start 0.120396 0.3048)
			(end 0.120396 0.2794)
			(stroke
				(width 0.1)
				(type default)
			)
			(layer "F.Fab")
		)
		(fp_line
			(start -0.12065 0.3048)
			(end -0.67945 0.3048)
			(stroke
				(width 0.1)
				(type default)
			)
			(layer "F.Fab")
		)
		(fp_line
			(start -0.67945 0.3048)
			(end -0.67945 -0.305054)
			(stroke
				(width 0.1)
				(type default)
			)
			(layer "F.Fab")
		)
		(pad "1" smd circle
			(at -0.40005 0 90)
			(size 0 0)
			(layers "F.Cu" "F.Mask" "F.Paste")
			(net "P3V3_AUX")
		)
		(pad "2" smd circle
			(at 0.40005 0 90)
			(size 0 0)
			(layers "F.Cu" "F.Mask" "F.Paste")
			(net "PWRGD_P1V8_AUX")
		)
	)
)
